(kicad_pcb
	(version 20221018)
	(generator pcbnew)
	(general
    (thickness 1.7403)
  )
	(paper "A4")
	(title_block
    (title "Data Center RDIMM DDR4 Tester")
    (date "2024-09-30")
    (rev "1.2.4")
		(comment 9 "footprints 11-19 of 690")
	)
	(layers
    (0 "F.Cu" signal)
    (1 "In1.Cu" power)
    (2 "In2.Cu" signal)
    (3 "In3.Cu" power)
    (4 "In4.Cu" power)
    (5 "In5.Cu" signal)
    (6 "In6.Cu" power)
    (7 "In7.Cu" signal)
    (8 "In8.Cu" power)
    (9 "In9.Cu" signal)
    (10 "In10.Cu" power)
    (31 "B.Cu" signal)
    (32 "B.Adhes" user "B.Adhesive")
    (33 "F.Adhes" user "F.Adhesive")
    (34 "B.Paste" user)
    (35 "F.Paste" user)
    (36 "B.SilkS" user "B.Silkscreen")
    (37 "F.SilkS" user "F.Silkscreen")
    (38 "B.Mask" user)
    (39 "F.Mask" user)
    (40 "Dwgs.User" user "User.Drawings")
    (41 "Cmts.User" user "User.Comments")
    (42 "Eco1.User" user "User.Eco1")
    (43 "Eco2.User" user "User.Eco2")
    (44 "Edge.Cuts" user)
    (45 "Margin" user)
    (46 "B.CrtYd" user "B.Courtyard")
    (47 "F.CrtYd" user "F.Courtyard")
    (48 "B.Fab" user)
    (49 "F.Fab" user)
  )
	(footprint "data-center-rdimm-ddr4-tester-footprints:R_0402_1005Metric" (layer "F.Cu")
    (at 142.536328 100.247157 90)
    (descr "Resistor SMD 0402")
    (tags "resistor SMD 0402")
    (property "Author" "Antmicro")
    (property "License" "Apache-2.0")
    (property "MPN" "CR0402-FX-22R0GLF")
    (property "Manufacturer" "Bourns")
    (property "Sheetfile" "interfaces.kicad_sch")
    (property "Sheetname" "Interfaces")
    (property "Tolerance" "1%")
    (property "Val" "22R")
    (property "ki_description" "22R resistor in 0402 package with 1% tolerance")
    (attr smd)
    (fp_text reference "R6" (at -1.098843 2.438672 90) (layer "F.SilkS")
        (effects (font (size 0.7 0.7) (thickness 0.15)) (justify left bottom))
    )
    (fp_text value "R_22R_0402" (at 0 1.4 90) (layer "F.Fab") hide
        (effects (font (size 0.7 0.7) (thickness 0.15)) (justify left bottom))
    )
    (fp_text user "${REFERENCE}" (at -0.95 3.168 90) (layer "F.Fab") hide
        (effects (font (size 0.7 0.7) (thickness 0.15)) (justify left bottom))
    )
    (fp_text user "License: Apache-2.0" (at -0.95 5.169 90) (layer "F.Fab") hide
        (effects (font (size 0.7 0.7) (thickness 0.15)) (justify left bottom))
    )
    (fp_text user "Author: Antmicro" (at -0.95 4.169 90) (layer "F.Fab") hide
        (effects (font (size 0.7 0.7) (thickness 0.15)) (justify left bottom))
    )
    (fp_rect (start -0.93 -0.47) (end 0.93 0.47)
      (stroke (width 0.05) (type solid)) (fill none) (layer "F.CrtYd"))
    (fp_rect (start -0.5 -0.25) (end 0.5 0.25)
      (stroke (width 0.15) (type solid)) (fill none) (layer "F.Fab"))
    (pad "1" smd roundrect (at -0.485 0 90) (size 0.59 0.64) (layers "F.Cu" "F.Paste" "F.Mask") (roundrect_rratio 0.25)
      (net 590 "Net-(U7-CDBUS0)") (pintype "passive"))
    (pad "2" smd roundrect (at 0.485 0 90) (size 0.59 0.64) (layers "F.Cu" "F.Paste" "F.Mask") (roundrect_rratio 0.25)
      (net 135 "UART0_RX") (pintype "passive"))
  )
	(footprint "data-center-rdimm-ddr4-tester-footprints:R_0402_1005Metric" (layer "F.Cu")
    (at 141.411328 100.247157 90)
    (descr "Resistor SMD 0402")
    (tags "resistor SMD 0402")
    (property "Author" "Antmicro")
    (property "License" "Apache-2.0")
    (property "MPN" "CR0402-FX-22R0GLF")
    (property "Manufacturer" "Bourns")
    (property "Sheetfile" "interfaces.kicad_sch")
    (property "Sheetname" "Interfaces")
    (property "Tolerance" "1%")
    (property "Val" "22R")
    (property "ki_description" "22R resistor in 0402 package with 1% tolerance")
    (attr smd)
    (fp_text reference "R7" (at -1.192843 -1.781328 90) (layer "F.SilkS")
        (effects (font (size 0.7 0.7) (thickness 0.15)) (justify left bottom))
    )
    (fp_text value "R_22R_0402" (at 0 1.4 90) (layer "F.Fab") hide
        (effects (font (size 0.7 0.7) (thickness 0.15)) (justify left bottom))
    )
    (fp_text user "License: Apache-2.0" (at -0.95 5.169 90) (layer "F.Fab") hide
        (effects (font (size 0.7 0.7) (thickness 0.15)) (justify left bottom))
    )
    (fp_text user "Author: Antmicro" (at -0.95 4.169 90) (layer "F.Fab") hide
        (effects (font (size 0.7 0.7) (thickness 0.15)) (justify left bottom))
    )
    (fp_text user "${REFERENCE}" (at -0.95 3.168 90) (layer "F.Fab") hide
        (effects (font (size 0.7 0.7) (thickness 0.15)) (justify left bottom))
    )
    (fp_rect (start -0.93 -0.47) (end 0.93 0.47)
      (stroke (width 0.05) (type solid)) (fill none) (layer "F.CrtYd"))
    (fp_rect (start -0.5 -0.25) (end 0.5 0.25)
      (stroke (width 0.15) (type solid)) (fill none) (layer "F.Fab"))
    (pad "1" smd roundrect (at -0.485 0 90) (size 0.59 0.64) (layers "F.Cu" "F.Paste" "F.Mask") (roundrect_rratio 0.25)
      (net 591 "Net-(U7-CDBUS1)") (pintype "passive"))
    (pad "2" smd roundrect (at 0.485 0 90) (size 0.59 0.64) (layers "F.Cu" "F.Paste" "F.Mask") (roundrect_rratio 0.25)
      (net 137 "UART0_TX") (pintype "passive"))
  )
	(footprint "data-center-rdimm-ddr4-tester-footprints:R_0402_1005Metric" (layer "F.Cu")
    (at 133.911328 102.622157 180)
    (descr "Resistor SMD 0402")
    (tags "resistor SMD 0402")
    (property "Author" "Antmicro")
    (property "License" "Apache-2.0")
    (property "MPN" "CR0402-FX-22R0GLF")
    (property "Manufacturer" "Bourns")
    (property "Sheetfile" "interfaces.kicad_sch")
    (property "Sheetname" "Interfaces")
    (property "Tolerance" "1%")
    (property "Val" "22R")
    (property "ki_description" "22R resistor in 0402 package with 1% tolerance")
    (attr smd)
    (fp_text reference "R8" (at 2.591328 -0.377843 180) (layer "F.SilkS")
        (effects (font (size 0.7 0.7) (thickness 0.15)) (justify left bottom))
    )
    (fp_text value "R_22R_0402" (at 0 1.4 180) (layer "F.Fab") hide
        (effects (font (size 0.7 0.7) (thickness 0.15)) (justify left bottom))
    )
    (fp_text user "License: Apache-2.0" (at -0.95 5.169 180) (layer "F.Fab") hide
        (effects (font (size 0.7 0.7) (thickness 0.15)) (justify left bottom))
    )
    (fp_text user "Author: Antmicro" (at -0.95 4.169 180) (layer "F.Fab") hide
        (effects (font (size 0.7 0.7) (thickness 0.15)) (justify left bottom))
    )
    (fp_text user "${REFERENCE}" (at -0.95 3.168 180) (layer "F.Fab") hide
        (effects (font (size 0.7 0.7) (thickness 0.15)) (justify left bottom))
    )
    (fp_rect (start -0.93 -0.47) (end 0.93 0.47)
      (stroke (width 0.05) (type solid)) (fill none) (layer "F.CrtYd"))
    (fp_rect (start -0.5 -0.25) (end 0.5 0.25)
      (stroke (width 0.15) (type solid)) (fill none) (layer "F.Fab"))
    (pad "1" smd roundrect (at -0.485 0 180) (size 0.59 0.64) (layers "F.Cu" "F.Paste" "F.Mask") (roundrect_rratio 0.25)
      (net 592 "Net-(U7-DDBUS0)") (pintype "passive"))
    (pad "2" smd roundrect (at 0.485 0 180) (size 0.59 0.64) (layers "F.Cu" "F.Paste" "F.Mask") (roundrect_rratio 0.25)
      (net 139 "UART1_RX") (pintype "passive"))
  )
	(footprint "data-center-rdimm-ddr4-tester-footprints:R_0402_1005Metric" (layer "F.Cu")
    (at 133.911328 105.872157 180)
    (descr "Resistor SMD 0402")
    (tags "resistor SMD 0402")
    (property "Author" "Antmicro")
    (property "License" "Apache-2.0")
    (property "MPN" "CR0402-FX-22R0GLF")
    (property "Manufacturer" "Bourns")
    (property "Sheetfile" "interfaces.kicad_sch")
    (property "Sheetname" "Interfaces")
    (property "Tolerance" "1%")
    (property "Val" "22R")
    (property "ki_description" "22R resistor in 0402 package with 1% tolerance")
    (attr smd)
    (fp_text reference "R37" (at 3.061328 -0.387843 180) (layer "F.SilkS")
        (effects (font (size 0.7 0.7) (thickness 0.15)) (justify left bottom))
    )
    (fp_text value "R_22R_0402" (at 0 1.4 180) (layer "F.Fab") hide
        (effects (font (size 0.7 0.7) (thickness 0.15)) (justify left bottom))
    )
    (fp_text user "License: Apache-2.0" (at -0.95 5.169 180) (layer "F.Fab") hide
        (effects (font (size 0.7 0.7) (thickness 0.15)) (justify left bottom))
    )
    (fp_text user "${REFERENCE}" (at -0.95 3.168 180) (layer "F.Fab") hide
        (effects (font (size 0.7 0.7) (thickness 0.15)) (justify left bottom))
    )
    (fp_text user "Author: Antmicro" (at -0.95 4.169 180) (layer "F.Fab") hide
        (effects (font (size 0.7 0.7) (thickness 0.15)) (justify left bottom))
    )
    (fp_rect (start -0.93 -0.47) (end 0.93 0.47)
      (stroke (width 0.05) (type solid)) (fill none) (layer "F.CrtYd"))
    (fp_rect (start -0.5 -0.25) (end 0.5 0.25)
      (stroke (width 0.15) (type solid)) (fill none) (layer "F.Fab"))
    (pad "1" smd roundrect (at -0.485 0 180) (size 0.59 0.64) (layers "F.Cu" "F.Paste" "F.Mask") (roundrect_rratio 0.25)
      (net 602 "Net-(U7-DDBUS1)") (pintype "passive"))
    (pad "2" smd roundrect (at 0.485 0 180) (size 0.59 0.64) (layers "F.Cu" "F.Paste" "F.Mask") (roundrect_rratio 0.25)
      (net 141 "UART1_TX") (pintype "passive"))
  )
	(footprint "data-center-rdimm-ddr4-tester-footprints:C_0402_1005Metric" (layer "F.Cu")
    (at 115.286328 99.122157 -90)
    (descr "Capacitor SMD 0402")
    (tags "capacitor SMD 0402")
    (property "Author" "Antmicro")
    (property "Dielectric" "")
    (property "License" "Apache-2.0")
    (property "MPN" "CC0402MRX5R5BB106")
    (property "Manufacturer" "Yaego")
    (property "Sheetfile" "supply.kicad_sch")
    (property "Sheetname" "Supply")
    (property "Val" "10u")
    (property "Voltage" "")
    (property "ki_description" " ")
    (attr smd)
    (fp_text reference "C38" (at -0.112157 1.426328 -90) (layer "F.SilkS")
        (effects (font (size 0.7 0.7) (thickness 0.15)) (justify left bottom))
    )
    (fp_text value "C_10u_0402" (at 0 1.4 -90) (layer "F.Fab") hide
        (effects (font (size 0.7 0.7) (thickness 0.15)) (justify left bottom))
    )
    (fp_text user "${REFERENCE}" (at -0.932 3.168 -90) (layer "F.Fab") hide
        (effects (font (size 0.7 0.7) (thickness 0.15)) (justify left bottom))
    )
    (fp_text user "License: Apache-2.0" (at -0.932 5.17 -90) (layer "F.Fab") hide
        (effects (font (size 0.7 0.7) (thickness 0.15)) (justify left bottom))
    )
    (fp_text user "Author: Antmicro" (at -0.932 4.17 -90) (layer "F.Fab") hide
        (effects (font (size 0.7 0.7) (thickness 0.15)) (justify left bottom))
    )
    (fp_rect (start -0.94 -0.47) (end 0.94 0.47)
      (stroke (width 0.05) (type solid)) (fill none) (layer "F.CrtYd"))
    (fp_rect (start -0.499 -0.249) (end 0.499 0.249)
      (stroke (width 0.15) (type solid)) (fill none) (layer "F.Fab"))
    (pad "1" smd roundrect (at -0.484 0 270) (size 0.59 0.64) (layers "F.Cu" "F.Paste" "F.Mask") (roundrect_rratio 0.25)
      (net 299 "VCC0V6") (pintype "passive"))
    (pad "2" smd roundrect (at 0.484 0 270) (size 0.59 0.64) (layers "F.Cu" "F.Paste" "F.Mask") (roundrect_rratio 0.25)
      (net 9 "GND") (pintype "passive"))
  )
	(footprint "data-center-rdimm-ddr4-tester-footprints:R_0402_1005Metric" (layer "F.Cu")
    (at 110.286328 115.997157)
    (descr "Resistor SMD 0402")
    (tags "resistor SMD 0402")
    (property "Author" "Antmicro")
    (property "License" "Apache-2.0")
    (property "MPN" "CR0402-FX-2433GLF")
    (property "Manufacturer" "Bourns")
    (property "Sheetfile" "supply.kicad_sch")
    (property "Sheetname" "Supply")
    (property "Tolerance" "1%")
    (property "Val" "243k")
    (property "ki_description" "243k resistor in 0402 package with 1% tolerance")
    (attr smd)
    (fp_text reference "R116" (at -1.447328 2.467843) (layer "F.SilkS")
        (effects (font (size 0.7 0.7) (thickness 0.15)) (justify left bottom))
    )
    (fp_text value "R_243k_0402" (at 0 1.4) (layer "F.Fab") hide
        (effects (font (size 0.7 0.7) (thickness 0.15)) (justify left bottom))
    )
    (fp_text user "License: Apache-2.0" (at -0.95 5.169) (layer "F.Fab") hide
        (effects (font (size 0.7 0.7) (thickness 0.15)) (justify left bottom))
    )
    (fp_text user "${REFERENCE}" (at -0.95 3.168) (layer "F.Fab") hide
        (effects (font (size 0.7 0.7) (thickness 0.15)) (justify left bottom))
    )
    (fp_text user "Author: Antmicro" (at -0.95 4.169) (layer "F.Fab") hide
        (effects (font (size 0.7 0.7) (thickness 0.15)) (justify left bottom))
    )
    (fp_rect (start -0.93 -0.47) (end 0.93 0.47)
      (stroke (width 0.05) (type solid)) (fill none) (layer "F.CrtYd"))
    (fp_rect (start -0.5 -0.25) (end 0.5 0.25)
      (stroke (width 0.15) (type solid)) (fill none) (layer "F.Fab"))
    (pad "1" smd roundrect (at -0.485 0) (size 0.59 0.64) (layers "F.Cu" "F.Paste" "F.Mask") (roundrect_rratio 0.25)
      (net 9 "GND") (pintype "passive"))
    (pad "2" smd roundrect (at 0.485 0) (size 0.59 0.64) (layers "F.Cu" "F.Paste" "F.Mask") (roundrect_rratio 0.25)
      (net 109 "Net-(IC1-RT{slash}CLK)") (pintype "passive"))
  )
	(footprint "data-center-rdimm-ddr4-tester-footprints:R_0402_1005Metric" (layer "F.Cu")
    (at 120.315 116.622157 180)
    (descr "Resistor SMD 0402")
    (tags "resistor SMD 0402")
    (property "Author" "Antmicro")
    (property "License" "Apache-2.0")
    (property "MPN" "CR0402-FX-49R9GLF")
    (property "Manufacturer" "Bourns")
    (property "Sheetfile" "supply.kicad_sch")
    (property "Sheetname" "Supply")
    (property "Tolerance" "1%")
    (property "Val" "49R9")
    (property "ki_description" "49R9 resistor in 0402 package with 1% tolerance")
    (attr smd)
    (fp_text reference "R126" (at 4.315 -3.607843 180) (layer "F.SilkS")
        (effects (font (size 0.7 0.7) (thickness 0.15)) (justify left bottom))
    )
    (fp_text value "R_49R9_0402" (at 0 1.4 180) (layer "F.Fab") hide
        (effects (font (size 0.7 0.7) (thickness 0.15)) (justify left bottom))
    )
    (fp_text user "${REFERENCE}" (at -0.95 3.168 180) (layer "F.Fab") hide
        (effects (font (size 0.7 0.7) (thickness 0.15)) (justify left bottom))
    )
    (fp_text user "Author: Antmicro" (at -0.95 4.169 180) (layer "F.Fab") hide
        (effects (font (size 0.7 0.7) (thickness 0.15)) (justify left bottom))
    )
    (fp_text user "License: Apache-2.0" (at -0.95 5.169 180) (layer "F.Fab") hide
        (effects (font (size 0.7 0.7) (thickness 0.15)) (justify left bottom))
    )
    (fp_rect (start -0.93 -0.47) (end 0.93 0.47)
      (stroke (width 0.05) (type solid)) (fill none) (layer "F.CrtYd"))
    (fp_rect (start -0.5 -0.25) (end 0.5 0.25)
      (stroke (width 0.15) (type solid)) (fill none) (layer "F.Fab"))
    (pad "1" smd roundrect (at -0.485 0 180) (size 0.59 0.64) (layers "F.Cu" "F.Paste" "F.Mask") (roundrect_rratio 0.25)
      (net 104 "VCC5V0") (pintype "passive"))
    (pad "2" smd roundrect (at 0.485 0 180) (size 0.59 0.64) (layers "F.Cu" "F.Paste" "F.Mask") (roundrect_rratio 0.25)
      (net 118 "Net-(R126-Pad2)") (pintype "passive"))
  )
	(footprint "data-center-rdimm-ddr4-tester-footprints:C_0603_1608Metric" (layer "F.Cu")
    (at 116.036328 86.160008 180)
    (descr "Capacitor SMD 0603")
    (tags "capacitor 0603")
    (property "Author" "Antmicro")
    (property "Dielectric" "")
    (property "License" "Apache-2.0")
    (property "MPN" "GRM188R60J226MEA0D")
    (property "Manufacturer" "Murata")
    (property "Sheetfile" "supply.kicad_sch")
    (property "Sheetname" "Supply")
    (property "Val" "22u")
    (property "Voltage" "")
    (property "ki_description" " ")
    (attr smd)
    (fp_text reference "C39" (at 1.666328 12.380008 180) (layer "F.SilkS")
        (effects (font (size 0.7 0.7) (thickness 0.15)) (justify left bottom))
    )
    (fp_text value "C_22u_0603" (at 0 1.6 180) (layer "F.Fab") hide
        (effects (font (size 0.7 0.7) (thickness 0.15)) (justify left bottom))
    )
    (fp_text user "License: Apache-2.0" (at -1.682 5.895 180) (layer "F.Fab") hide
        (effects (font (size 0.7 0.7) (thickness 0.15)) (justify left bottom))
    )
    (fp_text user "Author: Antmicro" (at -1.682 4.894 180) (layer "F.Fab") hide
        (effects (font (size 0.7 0.7) (thickness 0.15)) (justify left bottom))
    )
    (fp_text user "${REFERENCE}" (at -1.682 3.895 180) (layer "F.Fab") hide
        (effects (font (size 0.7 0.7) (thickness 0.15)) (justify left bottom))
    )
    (fp_line (start -0.3 -0.3) (end 0.3 -0.3)
      (stroke (width 0.15) (type solid)) (layer "F.SilkS"))
    (fp_line (start -0.3 0.3) (end 0.3 0.3)
      (stroke (width 0.15) (type solid)) (layer "F.SilkS"))
    (fp_rect (start -1.24 -0.7) (end 1.24 0.7)
      (stroke (width 0.05) (type solid)) (fill none) (layer "F.CrtYd"))
    (fp_rect (start -0.8 -0.4) (end 0.8 0.4)
      (stroke (width 0.15) (type solid)) (fill none) (layer "F.Fab"))
    (pad "1" smd roundrect (at -0.7 0 180) (size 0.6 0.8) (layers "F.Cu" "F.Paste" "F.Mask") (roundrect_rratio 0.2)
      (net 301 "VDD1V2") (pintype "passive"))
    (pad "2" smd roundrect (at 0.7 0 180) (size 0.6 0.8) (layers "F.Cu" "F.Paste" "F.Mask") (roundrect_rratio 0.2)
      (net 9 "GND") (pintype "passive"))
  )
	(footprint "data-center-rdimm-ddr4-tester-footprints:L_2020_5252Metric" (layer "F.Cu")
    (at 125.661328 94.497157)
    (property "Author" "Antmicro")
    (property "IMax" "")
    (property "ISat" "")
    (property "License" "Apache-2.0")
    (property "MPN" "IHLP2020BZER4R7M01")
    (property "Manufacturer" "Vishay")
    (property "Sheetfile" "supply.kicad_sch")
    (property "Sheetname" "Supply")
    (property "Size" "5.18x5.18")
    (property "Val" "4u7/2.8A")
    (attr smd)
    (fp_text reference "L1" (at 0 -3.3) (layer "F.SilkS")
        (effects (font (size 0.7 0.7) (thickness 0.15)) (justify left bottom))
    )
    (fp_text value "L_4u7_2.8A_2020" (at 0 4) (layer "F.Fab") hide
        (effects (font (size 0.7 0.7) (thickness 0.15)) (justify left bottom))
    )
    (fp_text user "License: Apache-2.0" (at -3.29 7.2) (layer "F.Fab") hide
        (effects (font (size 0.7 0.7) (thickness 0.15)) (justify left bottom))
    )
    (fp_text user "Author: Antmicro" (at -3.29 8.4) (layer "F.Fab") hide
        (effects (font (size 0.7 0.7) (thickness 0.15)) (justify left bottom))
    )
    (fp_text user "${REFERENCE}" (at -3.29 6) (layer "F.Fab") hide
        (effects (font (size 0.7 0.7) (thickness 0.15)) (justify left bottom))
    )
    (fp_line (start -2.999 -2.846) (end -2.999 -1.73)
      (stroke (width 0.15) (type solid)) (layer "F.SilkS"))
    (fp_line (start -2.999 1.729) (end -2.999 2.843)
      (stroke (width 0.15) (type solid)) (layer "F.SilkS"))
    (fp_line (start -2.999 2.843) (end 2.996 2.843)
      (stroke (width 0.15) (type solid)) (layer "F.SilkS"))
    (fp_line (start 2.996 -2.846) (end -2.999 -2.846)
      (stroke (width 0.15) (type solid)) (layer "F.SilkS"))
    (fp_line (start 2.996 -1.73) (end 2.996 -2.846)
      (stroke (width 0.15) (type solid)) (layer "F.SilkS"))
    (fp_line (start 2.996 2.843) (end 2.996 1.729)
      (stroke (width 0.15) (type solid)) (layer "F.SilkS"))
    (fp_line (start -3.29 -1.67) (end -3.13 -1.67)
      (stroke (width 0.05) (type solid)) (layer "F.CrtYd"))
    (fp_line (start -3.29 1.65) (end -3.29 -1.67)
      (stroke (width 0.05) (type solid)) (layer "F.CrtYd"))
    (fp_line (start -3.13 -2.98) (end 3.12 -2.98)
      (stroke (width 0.05) (type solid)) (layer "F.CrtYd"))
    (fp_line (start -3.13 -1.67) (end -3.13 -2.98)
      (stroke (width 0.05) (type solid)) (layer "F.CrtYd"))
    (fp_line (start -3.13 1.65) (end -3.29 1.65)
      (stroke (width 0.05) (type solid)) (layer "F.CrtYd"))
    (fp_line (start -3.13 2.97) (end -3.13 1.65)
      (stroke (width 0.05) (type solid)) (layer "F.CrtYd"))
    (fp_line (start 3.12 -2.98) (end 3.12 -1.67)
      (stroke (width 0.05) (type solid)) (layer "F.CrtYd"))
    (fp_line (start 3.12 -1.67) (end 3.26 -1.67)
      (stroke (width 0.05) (type solid)) (layer "F.CrtYd"))
    (fp_line (start 3.12 1.65) (end 3.12 2.97)
      (stroke (width 0.05) (type solid)) (layer "F.CrtYd"))
    (fp_line (start 3.12 2.97) (end -3.13 2.97)
      (stroke (width 0.05) (type solid)) (layer "F.CrtYd"))
    (fp_line (start 3.26 -1.67) (end 3.26 1.65)
      (stroke (width 0.05) (type solid)) (layer "F.CrtYd"))
    (fp_line (start 3.26 1.65) (end 3.12 1.65)
      (stroke (width 0.05) (type solid)) (layer "F.CrtYd"))
    (fp_line (start -2.871 -2.718) (end -2.871 2.717)
      (stroke (width 0.15) (type solid)) (layer "F.Fab"))
    (fp_line (start -2.871 2.717) (end 2.87 2.717)
      (stroke (width 0.15) (type solid)) (layer "F.Fab"))
    (fp_line (start 2.87 -2.718) (end -2.871 -2.718)
      (stroke (width 0.15) (type solid)) (layer "F.Fab"))
    (fp_line (start 2.87 2.717) (end 2.87 -2.718)
      (stroke (width 0.15) (type solid)) (layer "F.Fab"))
    (pad "1" smd rect (at -2.032 0 90) (size 2.794 1.9812) (layers "F.Cu" "F.Paste" "F.Mask")
      (net 571 "Net-(U2-SW_VPP)") (pintype "passive"))
    (pad "2" smd rect (at 2.031 0 90) (size 2.794 1.9812) (layers "F.Cu" "F.Paste" "F.Mask")
      (net 303 "VCC2V5") (pintype "passive"))
  )
)
